(kicad_pcb
	(version 20260206)
	(generator "pcbnew")
	(generator_version "10.0")
	(general
		(thickness 1.6)
		(legacy_teardrops no)
	)
	(paper "A4")
	(title_block
		(title "Bryce Canyon_R.DPB_16317-1_OCP.brd")
		(comment 1 "Bryce Canyon / footprints 1934-1936 of 2099")
	)
	(layers
		(0 "F.Cu" signal "TOP")
		(4 "In1.Cu" signal "L2GND")
		(6 "In2.Cu" signal "L3")
		(8 "In3.Cu" signal "L4VCC")
		(10 "In4.Cu" signal "L5VCC")
		(12 "In5.Cu" signal "L6")
		(14 "In6.Cu" signal "L7GND")
		(2 "B.Cu" signal "BOTTOM")
		(9 "F.Adhes" user "F.Adhesive")
		(11 "B.Adhes" user "B.Adhesive")
		(13 "F.Paste" user "Package Geometry/Pastemask Top")
		(15 "B.Paste" user "Package Geometry/Pastemask Bottom")
		(5 "F.SilkS" user "Ref Des/Silkscreen Top")
		(7 "B.SilkS" user "Ref Des/Silkscreen Bottom")
		(1 "F.Mask" user "Board Geometry/Soldermask Top")
		(3 "B.Mask" user "Board Geometry/Soldermask Bottom")
		(17 "Dwgs.User" user "User.Drawings")
		(19 "Cmts.User" user "User.Comments")
		(21 "Eco1.User" user "User.Eco1")
		(23 "Eco2.User" user "User.Eco2")
		(25 "Edge.Cuts" user "Board Geometry/Outline")
		(27 "Margin" user)
		(31 "F.CrtYd" user "Package Geometry/Place Bound Top")
		(29 "B.CrtYd" user "Package Geometry/Place Bound Bottom")
		(35 "F.Fab" user "Ref Des/Assembly Top")
		(33 "B.Fab" user "Ref Des/Assembly Bottom")
	)
	(footprint ""
		(layer "F.Cu")
		(at 357.100124 -258.910074 -90)
		(property "Reference" "HDDSAS7"
			(at 0 0 270)
			(layer "F.SilkS")
			(hide yes)
			(effects
				(font
					(size 1.27 1.27)
				)
			)
		)
		(property "Value" "SKT-SAS15P-14P-45-GP"
			(at -20.7645 -8.9789 270)
			(unlocked yes)
			(layer "F.Fab")
			(hide yes)
			(effects
				(font
					(size 1.016 1.016)
					(thickness 0.1524)
				)
			)
		)
		(property "Device Type" "10120818-001C-TRLF"
			(at -20.7645 -10.5029 270)
			(unlocked yes)
			(layer "F.Fab")
			(hide yes)
			(effects
				(font
					(size 1.016 1.016)
					(thickness 0.1524)
				)
			)
		)
		(duplicate_pad_numbers_are_jumpers no)
		(fp_line
			(start 1.651 4.2926)
			(end 1.651 3.0099)
			(stroke
				(width 0.1524)
				(type default)
			)
			(layer "F.SilkS")
		)
		(fp_line
			(start 8.509 4.2926)
			(end 1.651 4.2926)
			(stroke
				(width 0.1524)
				(type default)
			)
			(layer "F.SilkS")
		)
		(fp_line
			(start -23.4188 3.0099)
			(end -23.4188 -3.2512)
			(stroke
				(width 0.1524)
				(type default)
			)
			(layer "F.SilkS")
		)
		(fp_line
			(start 1.651 3.0099)
			(end -23.4188 3.0099)
			(stroke
				(width 0.1524)
				(type default)
			)
			(layer "F.SilkS")
		)
		(fp_line
			(start 8.509 3.0099)
			(end 8.509 4.2926)
			(stroke
				(width 0.1524)
				(type default)
			)
			(layer "F.SilkS")
		)
		(fp_line
			(start 23.4188 3.0099)
			(end 8.509 3.0099)
			(stroke
				(width 0.1524)
				(type default)
			)
			(layer "F.SilkS")
		)
		(fp_line
			(start -23.4188 -3.2512)
			(end 23.4188 -3.2512)
			(stroke
				(width 0.1524)
				(type default)
			)
			(layer "F.SilkS")
		)
		(fp_line
			(start 23.4188 -3.2512)
			(end 23.4188 3.0099)
			(stroke
				(width 0.1524)
				(type default)
			)
			(layer "F.SilkS")
		)
		(fp_line
			(start 15.5067 -3.3401)
			(end 16.2687 -3.3401)
			(stroke
				(width 0.3302)
				(type default)
			)
			(layer "F.SilkS")
		)
		(fp_poly
			(pts
				(xy 15.868904 -3.230372) (xy 16.503904 -3.865372) (xy 15.233904 -3.865372)
			)
			(stroke
				(width 0)
				(type default)
			)
			(fill yes)
			(layer "F.SilkS")
		)
		(fp_poly
			(pts
				(xy -22.8727 -2.7559) (xy 22.8727 -2.7559) (xy 22.8727 2.7559) (xy 8.255 2.7559) (xy 8.255 3.5179)
				(xy 1.905 3.5179) (xy 1.905 2.7559) (xy -22.8727 2.7559)
			)
			(stroke
				(width 0)
				(type default)
			)
			(fill no)
			(layer "F.CrtYd")
		)
		(fp_poly
			(pts
				(xy 1.397 4.5466) (xy 1.397 3.2639) (xy -23.6728 3.2639) (xy -23.6728 -3.5052) (xy 23.6728 -3.5052)
				(xy 23.6728 -0.00635) (xy 22.8727 -0.00635) (xy 22.8727 -2.7559) (xy -22.8727 -2.7559) (xy -22.8727 2.7559)
				(xy 1.905 2.7559) (xy 1.905 3.5179) (xy 8.255 3.5179) (xy 8.255 2.7559) (xy 22.8727 2.7559) (xy 22.8727 0.00635)
				(xy 23.6728 0.00635) (xy 23.6728 3.2639) (xy 8.763 3.2639) (xy 8.763 4.5466)
			)
			(stroke
				(width 0)
				(type default)
			)
			(fill no)
			(layer "F.CrtYd")
		)
		(fp_poly
			(pts
				(xy 1.397 4.5466) (xy 1.397 3.2639) (xy -23.6728 3.2639) (xy -23.6728 -3.5052) (xy 23.6728 -3.5052)
				(xy 23.6728 3.2639) (xy 8.763 3.2639) (xy 8.763 4.5466)
			)
			(stroke
				(width 0)
				(type default)
			)
			(fill no)
			(layer "F.Fab")
		)
		(pad "" np_thru_hole circle
			(at -18.874994 0 270)
			(size 0.254 0.254)
			(drill 1.3462)
			(layers "*.Cu" "*.Mask")
			(clearance 0.9017)
			(thermal_gap 0.9017)
		)
		(pad "" np_thru_hole circle
			(at 18.874994 0 270)
			(size 0.254 0.254)
			(drill 0.9398)
			(layers "*.Cu" "*.Mask")
			(clearance 0.6985)
			(thermal_gap 0.6985)
		)
		(pad "G1" smd rect
			(at 21.874988 0 270)
			(size 2.5908 2.5908)
			(layers "F.Cu" "F.Mask" "F.Paste")
			(net "GND")
		)
		(pad "G2" smd rect
			(at -21.874988 0 270)
			(size 2.5908 2.5908)
			(layers "F.Cu" "F.Mask" "F.Paste")
			(net "GND")
		)
		(pad "P1" smd rect
			(at 1.905 -1.82499 270)
			(size 0.6096 2.3622)
			(layers "F.Cu" "F.Mask" "F.Paste")
			(net "Net_1594")
		)
		(pad "P2" smd rect
			(at 0.635 -1.82499 270)
			(size 0.6096 2.3622)
			(layers "F.Cu" "F.Mask" "F.Paste")
			(net "Net_1595")
		)
		(pad "P3" smd rect
			(at -0.635 -1.82499 270)
			(size 0.6096 2.3622)
			(layers "F.Cu" "F.Mask" "F.Paste")
			(net "Net_1596")
		)
		(pad "P4" smd rect
			(at -1.905 -1.82499 270)
			(size 0.6096 2.3622)
			(layers "F.Cu" "F.Mask" "F.Paste")
			(net "GND")
		)
		(pad "P5" smd rect
			(at -3.175 -1.82499 270)
			(size 0.6096 2.3622)
			(layers "F.Cu" "F.Mask" "F.Paste")
			(net "HDD_PRSNT_7")
		)
		(pad "P6" smd rect
			(at -4.445 -1.82499 270)
			(size 0.6096 2.3622)
			(layers "F.Cu" "F.Mask" "F.Paste")
			(net "GND")
		)
		(pad "P7" smd rect
			(at -5.715 -1.82499 270)
			(size 0.6096 2.3622)
			(layers "F.Cu" "F.Mask" "F.Paste")
			(net "5V_PRE_7")
		)
		(pad "P8" smd rect
			(at -6.985 -1.82499 270)
			(size 0.6096 2.3622)
			(layers "F.Cu" "F.Mask" "F.Paste")
			(net "P5V_HDD7")
		)
		(pad "P9" smd rect
			(at -8.255 -1.82499 270)
			(size 0.6096 2.3622)
			(layers "F.Cu" "F.Mask" "F.Paste")
			(net "P5V_HDD7")
		)
		(pad "P10" smd rect
			(at -9.525 -1.82499 270)
			(size 0.6096 2.3622)
			(layers "F.Cu" "F.Mask" "F.Paste")
			(net "GND")
		)
		(pad "P11" smd rect
			(at -10.795 -1.82499 270)
			(size 0.6096 2.3622)
			(layers "F.Cu" "F.Mask" "F.Paste")
			(net "ACT_HDD_7")
		)
		(pad "P12" smd rect
			(at -12.065 -1.82499 270)
			(size 0.6096 2.3622)
			(layers "F.Cu" "F.Mask" "F.Paste")
			(net "GND")
		)
		(pad "P13" smd rect
			(at -13.335 -1.82499 270)
			(size 0.6096 2.3622)
			(layers "F.Cu" "F.Mask" "F.Paste")
			(net "12V_PRE_7")
		)
		(pad "P14" smd rect
			(at -14.605 -1.82499 270)
			(size 0.6096 2.3622)
			(layers "F.Cu" "F.Mask" "F.Paste")
			(net "P12V_HDD7")
		)
		(pad "P15" smd rect
			(at -15.875 -1.82499 270)
			(size 0.6096 2.3622)
			(layers "F.Cu" "F.Mask" "F.Paste")
			(net "P12V_HDD7")
		)
		(pad "S1" smd rect
			(at 15.875 -1.82499 270)
			(size 0.6096 2.3622)
			(layers "F.Cu" "F.Mask" "F.Paste")
			(net "GND")
		)
		(pad "S2" smd rect
			(at 14.605 -1.82499 270)
			(size 0.6096 2.3622)
			(layers "F.Cu" "F.Mask" "F.Paste")
			(net "SAS_HDD_RX_P7")
		)
		(pad "S3" smd rect
			(at 13.335 -1.82499 270)
			(size 0.6096 2.3622)
			(layers "F.Cu" "F.Mask" "F.Paste")
			(net "SAS_HDD_RX_N7")
		)
		(pad "S4" smd rect
			(at 12.065 -1.82499 270)
			(size 0.6096 2.3622)
			(layers "F.Cu" "F.Mask" "F.Paste")
			(net "GND")
		)
		(pad "S5" smd rect
			(at 10.795 -1.82499 270)
			(size 0.6096 2.3622)
			(layers "F.Cu" "F.Mask" "F.Paste")
			(net "PHY_DRV_B_TO_SCC_B_7_DN")
		)
		(pad "S6" smd rect
			(at 9.525 -1.82499 270)
			(size 0.6096 2.3622)
			(layers "F.Cu" "F.Mask" "F.Paste")
			(net "PHY_DRV_B_TO_SCC_B_7_DP")
		)
		(pad "S7" smd rect
			(at 8.255 -1.82499 270)
			(size 0.6096 2.3622)
			(layers "F.Cu" "F.Mask" "F.Paste")
			(net "GND")
		)
		(pad "S8" smd rect
			(at 7.480046 2.845054 270)
			(size 0.508 2.3622)
			(layers "F.Cu" "F.Mask" "F.Paste")
			(net "GND")
		)
		(pad "S9" smd rect
			(at 6.679946 2.845054 270)
			(size 0.508 2.3622)
			(layers "F.Cu" "F.Mask" "F.Paste")
			(net "Net_465")
		)
		(pad "S10" smd rect
			(at 5.8801 2.845054 270)
			(size 0.508 2.3622)
			(layers "F.Cu" "F.Mask" "F.Paste")
			(net "Net_357")
		)
		(pad "S11" smd rect
			(at 5.08 2.845054 270)
			(size 0.508 2.3622)
			(layers "F.Cu" "F.Mask" "F.Paste")
			(net "GND")
		)
		(pad "S12" smd rect
			(at 4.2799 2.845054 270)
			(size 0.508 2.3622)
			(layers "F.Cu" "F.Mask" "F.Paste")
			(net "Net_393")
		)
		(pad "S13" smd rect
			(at 3.480054 2.845054 270)
			(size 0.508 2.3622)
			(layers "F.Cu" "F.Mask" "F.Paste")
			(net "Net_429")
		)
		(pad "S14" smd rect
			(at 2.679954 2.845054 270)
			(size 0.508 2.3622)
			(layers "F.Cu" "F.Mask" "F.Paste")
			(net "GND")
		)
		(zone
			(layer "F.Cu")
			(hatch none 0.5)
			(connect_pads
				(clearance 0)
			)
			(min_thickness 0.25)
			(keepout
				(tracks allowed)
				(vias not_allowed)
				(pads allowed)
				(copperpour not_allowed)
				(footprints allowed)
			)
			(placement
				(enabled no)
				(sheetname "")
			)
			(fill
				(thermal_gap 0.5)
				(thermal_bridge_width 0.5)
				(island_removal_mode 0)
			)
			(polygon
				(pts
					(xy 360.757724 -275.648674) (xy 353.683824 -275.648674) (xy 353.683824 -282.582874) (xy 354.788724 -282.582874)
					(xy 354.788724 -278.468074) (xy 359.411524 -278.468074) (xy 359.411524 -282.582874) (xy 360.757724 -282.582874)
				)
			)
		)
		(zone
			(layer "F.Cu")
			(hatch none 0.5)
			(connect_pads
				(clearance 0)
			)
			(min_thickness 0.25)
			(keepout
				(tracks not_allowed)
				(vias allowed)
				(pads allowed)
				(copperpour not_allowed)
				(footprints allowed)
			)
			(placement
				(enabled no)
				(sheetname "")
			)
			(fill
				(thermal_gap 0.5)
				(thermal_bridge_width 0.5)
				(island_removal_mode 0)
			)
			(polygon
				(pts
					(xy 360.757724 -275.648674) (xy 353.683824 -275.648674) (xy 353.683824 -282.582874) (xy 354.788724 -282.582874)
					(xy 354.788724 -278.468074) (xy 359.411524 -278.468074) (xy 359.411524 -282.582874) (xy 360.757724 -282.582874)
				)
			)
		)
		(zone
			(layer "F.Cu")
			(hatch none 0.5)
			(connect_pads
				(clearance 0)
			)
			(min_thickness 0.25)
			(keepout
				(tracks not_allowed)
				(vias allowed)
				(pads allowed)
				(copperpour not_allowed)
				(footprints allowed)
			)
			(placement
				(enabled no)
				(sheetname "")
			)
			(fill
				(thermal_gap 0.5)
				(thermal_bridge_width 0.5)
				(island_removal_mode 0)
			)
			(polygon
				(pts
					(xy 360.757724 -242.171474) (xy 353.683824 -242.171474) (xy 353.683824 -235.237274) (xy 354.788724 -235.237274)
					(xy 354.788724 -239.352074) (xy 359.411524 -239.352074) (xy 359.411524 -235.237274) (xy 360.757724 -235.237274)
				)
			)
		)
		(zone
			(layer "F.Cu")
			(hatch none 0.5)
			(connect_pads
				(clearance 0)
			)
			(min_thickness 0.25)
			(keepout
				(tracks allowed)
				(vias not_allowed)
				(pads allowed)
				(copperpour not_allowed)
				(footprints allowed)
			)
			(placement
				(enabled no)
				(sheetname "")
			)
			(fill
				(thermal_gap 0.5)
				(thermal_bridge_width 0.5)
				(island_removal_mode 0)
			)
			(polygon
				(pts
					(xy 360.757724 -242.171474) (xy 353.683824 -242.171474) (xy 353.683824 -235.237274) (xy 354.788724 -235.237274)
					(xy 354.788724 -239.352074) (xy 359.411524 -239.352074) (xy 359.411524 -235.237274) (xy 360.757724 -235.237274)
				)
			)
		)
		(zone
			(layers "F.Cu" "B.Cu" "In1.Cu" "In2.Cu" "In3.Cu" "In4.Cu" "In5.Cu" "In6.Cu")
			(hatch none 0.5)
			(connect_pads
				(clearance 0)
			)
			(min_thickness 0.25)
			(keepout
				(tracks not_allowed)
				(vias allowed)
				(pads allowed)
				(copperpour not_allowed)
				(footprints allowed)
			)
			(placement
				(enabled no)
				(sheetname "")
			)
			(fill
				(thermal_gap 0.5)
				(thermal_bridge_width 0.5)
				(island_removal_mode 0)
			)
			(polygon
				(pts
					(arc
						(start 357.874824 -240.03508)
						(mid 356.325424 -240.03508)
						(end 357.874824 -240.03508)
					)
				)
			)
		)
		(zone
			(layers "F.Cu" "B.Cu" "In1.Cu" "In2.Cu" "In3.Cu" "In4.Cu" "In5.Cu" "In6.Cu")
			(hatch none 0.5)
			(connect_pads
				(clearance 0)
			)
			(min_thickness 0.25)
			(keepout
				(tracks not_allowed)
				(vias allowed)
				(pads allowed)
				(copperpour not_allowed)
				(footprints allowed)
			)
			(placement
				(enabled no)
				(sheetname "")
			)
			(fill
				(thermal_gap 0.5)
				(thermal_bridge_width 0.5)
				(island_removal_mode 0)
			)
			(polygon
				(pts
					(arc
						(start 358.078024 -277.785068)
						(mid 356.122224 -277.785068)
						(end 358.078024 -277.785068)
					)
				)
			)
		)
	)
	(footprint ""
		(layer "F.Cu")
		(at 159.512 -31.623 180)
		(property "Reference" "R714"
			(at 0 0 180)
			(layer "F.SilkS")
			(hide yes)
			(effects
				(font
					(size 1.27 1.27)
				)
			)
		)
		(property "Value" "10KR2F-2-GP"
			(at 0.064008 -3.993896 180)
			(unlocked yes)
			(layer "F.Fab")
			(hide yes)
			(effects
				(font
					(size 1.016 1.016)
					(thickness 0.1524)
				)
			)
		)
		(property "Device Type" "R402H16"
			(at 0.064008 -5.517896 180)
			(unlocked yes)
			(layer "F.Fab")
			(hide yes)
			(effects
				(font
					(size 1.016 1.016)
					(thickness 0.1524)
				)
			)
		)
		(duplicate_pad_numbers_are_jumpers no)
		(fp_line
			(start 0.508 -0.9398)
			(end -0.508 -0.9398)
			(stroke
				(width 0.1524)
				(type default)
			)
			(layer "F.SilkS")
		)
		(fp_line
			(start -0.508 -0.9398)
			(end -0.508 0.9398)
			(stroke
				(width 0.1524)
				(type default)
			)
			(layer "F.SilkS")
		)
		(fp_rect
			(start -0.508 0.9398)
			(end 0.508 -0.9398)
			(stroke
				(width 0)
				(type default)
			)
			(fill no)
			(layer "F.CrtYd")
		)
		(fp_rect
			(start -0.508 0.9398)
			(end 0.508 -0.9398)
			(stroke
				(width 0)
				(type default)
			)
			(fill no)
			(layer "F.Fab")
		)
		(pad "1" smd custom
			(at 0 -0.4445 180)
			(size 0.1397 0.1397)
			(layers "F.Cu" "F.Mask" "F.Paste")
			(net "P3V3_STBY_B")
			(options
				(clearance outline)
				(anchor circle)
			)
			(primitives
				(gr_poly
					(pts
						(arc
							(start -0.1778 -0.2794)
							(mid -0.249642 -0.249642)
							(end -0.2794 -0.1778)
						)
						(arc
							(start -0.2794 0.1778)
							(mid -0.249642 0.249642)
							(end -0.1778 0.2794)
						)
						(arc
							(start 0.1778 0.2794)
							(mid 0.249642 0.249642)
							(end 0.2794 0.1778)
						)
						(arc
							(start 0.2794 -0.1778)
							(mid 0.249642 -0.249642)
							(end 0.1778 -0.2794)
						)
					)
					(width 0)
					(fill yes)
				)
			)
		)
		(pad "2" smd custom
			(at 0 0.4445 180)
			(size 0.1397 0.1397)
			(layers "F.Cu" "F.Mask" "F.Paste")
			(net "HDD_PRSNT_28")
			(options
				(clearance outline)
				(anchor circle)
			)
			(primitives
				(gr_poly
					(pts
						(arc
							(start -0.1778 -0.2794)
							(mid -0.249642 -0.249642)
							(end -0.2794 -0.1778)
						)
						(arc
							(start -0.2794 0.1778)
							(mid -0.249642 0.249642)
							(end -0.1778 0.2794)
						)
						(arc
							(start 0.1778 0.2794)
							(mid 0.249642 0.249642)
							(end 0.2794 0.1778)
						)
						(arc
							(start 0.2794 -0.1778)
							(mid 0.249642 -0.249642)
							(end 0.1778 -0.2794)
						)
					)
					(width 0)
					(fill yes)
				)
			)
		)
	)
	(footprint ""
		(layer "F.Cu")
		(at 133.7818 -368.8334 90)
		(property "Reference" "R938"
			(at 0 0 90)
			(layer "F.SilkS")
			(hide yes)
			(effects
				(font
					(size 1.27 1.27)
				)
			)
		)
		(property "Value" "4K7R2F-GP"
			(at 0.064008 -3.993896 90)
			(unlocked yes)
			(layer "F.Fab")
			(hide yes)
			(effects
				(font
					(size 1.016 1.016)
					(thickness 0.1524)
				)
			)
		)
		(property "Device Type" "R402H16"
			(at 0.064008 -5.517896 90)
			(unlocked yes)
			(layer "F.Fab")
			(hide yes)
			(effects
				(font
					(size 1.016 1.016)
					(thickness 0.1524)
				)
			)
		)
		(duplicate_pad_numbers_are_jumpers no)
		(fp_line
			(start 0.508 -0.9398)
			(end -0.508 -0.9398)
			(stroke
				(width 0.1524)
				(type default)
			)
			(layer "F.SilkS")
		)
		(fp_line
			(start -0.508 -0.9398)
			(end -0.508 0.9398)
			(stroke
				(width 0.1524)
				(type default)
			)
			(layer "F.SilkS")
		)
		(fp_rect
			(start -0.508 0.9398)
			(end 0.508 -0.9398)
			(stroke
				(width 0)
				(type default)
			)
			(fill no)
			(layer "F.CrtYd")
		)
		(fp_rect
			(start -0.508 0.9398)
			(end 0.508 -0.9398)
			(stroke
				(width 0)
				(type default)
			)
			(fill no)
			(layer "F.Fab")
		)
		(pad "1" smd custom
			(at 0 -0.4445 90)
			(size 0.1397 0.1397)
			(layers "F.Cu" "F.Mask" "F.Paste")
			(net "P12V_IN")
			(options
				(clearance outline)
				(anchor circle)
			)
			(primitives
				(gr_poly
					(pts
						(arc
							(start -0.1778 -0.2794)
							(mid -0.249642 -0.249642)
							(end -0.2794 -0.1778)
						)
						(arc
							(start -0.2794 0.1778)
							(mid -0.249642 0.249642)
							(end -0.1778 0.2794)
						)
						(arc
							(start 0.1778 0.2794)
							(mid 0.249642 0.249642)
							(end 0.2794 0.1778)
						)
						(arc
							(start 0.2794 -0.1778)
							(mid 0.249642 -0.249642)
							(end 0.1778 -0.2794)
						)
					)
					(width 0)
					(fill yes)
				)
			)
		)
		(pad "2" smd custom
			(at 0 0.4445 90)
			(size 0.1397 0.1397)
			(layers "F.Cu" "F.Mask" "F.Paste")
			(net "FAN_1_TACH1")
			(options
				(clearance outline)
				(anchor circle)
			)
			(primitives
				(gr_poly
					(pts
						(arc
							(start -0.1778 -0.2794)
							(mid -0.249642 -0.249642)
							(end -0.2794 -0.1778)
						)
						(arc
							(start -0.2794 0.1778)
							(mid -0.249642 0.249642)
							(end -0.1778 0.2794)
						)
						(arc
							(start 0.1778 0.2794)
							(mid 0.249642 0.249642)
							(end 0.2794 0.1778)
						)
						(arc
							(start 0.2794 -0.1778)
							(mid 0.249642 -0.249642)
							(end 0.1778 -0.2794)
						)
					)
					(width 0)
					(fill yes)
				)
			)
		)
	)
)
